(kicad_pcb
	(version 20241229)
	(generator "pcbnew")
	(generator_version "9.0")
	(general
		(thickness 1.6296)
		(legacy_teardrops no)
	)
	(paper "A3")
	(title_block
		(title "Thunderbolt to 10GbE adapter")
		(date "2026-04-21")
		(rev "1.1.0")
		(company "Antmicro Ltd")
		(comment 1 "www.antmicro.com")
		(comment 9 "footprints 611-615 of 703")
	)
	(layers
		(0 "F.Cu" signal)
		(4 "In1.Cu" signal)
		(6 "In2.Cu" signal)
		(8 "In3.Cu" signal)
		(10 "In4.Cu" signal)
		(12 "In5.Cu" signal)
		(14 "In6.Cu" signal)
		(2 "B.Cu" signal)
		(9 "F.Adhes" user "F.Adhesive")
		(11 "B.Adhes" user "B.Adhesive")
		(13 "F.Paste" user)
		(15 "B.Paste" user)
		(5 "F.SilkS" user "F.Silkscreen")
		(7 "B.SilkS" user "B.Silkscreen")
		(1 "F.Mask" user)
		(3 "B.Mask" user)
		(17 "Dwgs.User" user "User.Drawings")
		(19 "Cmts.User" user "User.Comments")
		(21 "Eco1.User" user "User.Eco1")
		(23 "Eco2.User" user "User.Eco2")
		(25 "Edge.Cuts" user)
		(27 "Margin" user)
		(31 "F.CrtYd" user "F.Courtyard")
		(29 "B.CrtYd" user "B.Courtyard")
		(35 "F.Fab" user)
		(33 "B.Fab" user)
	)
	(footprint "antmicro-footprints:C_0402_1005Metric"
		(layer "B.Cu")
		(at 151.181867 76.260117 180)
		(descr "Capacitor SMD 0402")
		(tags "capacitor SMD 0402")
		(property "Reference" "C211"
			(at -20.368136 -9.464883 0)
			(layer "B.SilkS")
			(effects
				(font
					(size 0.7 0.7)
					(thickness 0.15)
				)
				(justify mirror)
			)
		)
		(property "Value" "C_1u_25V_0402"
			(at -1.022927 -2.155213 0)
			(layer "B.Fab")
			(effects
				(font
					(size 0.7 0.7)
					(thickness 0.15)
				)
				(justify left bottom mirror)
			)
		)
		(property "Datasheet" "https://www.murata.com/products/productdetail?partno=GRM155R61E105KE11%23"
			(at 0 0 0)
			(layer "B.Fab")
			(hide yes)
			(effects
				(font
					(size 1.27 1.27)
					(thickness 0.15)
				)
				(justify mirror)
			)
		)
		(property "Description" "SMD Multilayer Ceramic Capacitor, 1 µF, 25 V, 0402 [1005 Metric], ± 10%, X5R, GRM Series"
			(at 0 0 0)
			(layer "B.Fab")
			(hide yes)
			(effects
				(font
					(size 1.27 1.27)
					(thickness 0.15)
				)
				(justify mirror)
			)
		)
		(property "MPN" "GRM155R61E105KE11J"
			(at 0 0 180)
			(unlocked yes)
			(layer "B.Fab")
			(hide yes)
			(effects
				(font
					(size 1 1)
					(thickness 0.15)
				)
				(justify mirror)
			)
		)
		(property "Manufacturer" "Murata"
			(at 0 0 180)
			(unlocked yes)
			(layer "B.Fab")
			(hide yes)
			(effects
				(font
					(size 1 1)
					(thickness 0.15)
				)
				(justify mirror)
			)
		)
		(property "License" "Apache-2.0"
			(at 0 0 180)
			(unlocked yes)
			(layer "B.Fab")
			(hide yes)
			(effects
				(font
					(size 1 1)
					(thickness 0.15)
				)
				(justify mirror)
			)
		)
		(property "Author" "Antmicro"
			(at 0 0 180)
			(unlocked yes)
			(layer "B.Fab")
			(hide yes)
			(effects
				(font
					(size 1 1)
					(thickness 0.15)
				)
				(justify mirror)
			)
		)
		(property "Val" "1u"
			(at 0 0 180)
			(unlocked yes)
			(layer "B.Fab")
			(hide yes)
			(effects
				(font
					(size 1 1)
					(thickness 0.15)
				)
				(justify mirror)
			)
		)
		(property "Voltage" "25V"
			(at 0 0 180)
			(unlocked yes)
			(layer "B.Fab")
			(hide yes)
			(effects
				(font
					(size 1 1)
					(thickness 0.15)
				)
				(justify mirror)
			)
		)
		(property "Dielectric" "X5R"
			(at 0 0 180)
			(unlocked yes)
			(layer "B.Fab")
			(hide yes)
			(effects
				(font
					(size 1 1)
					(thickness 0.15)
				)
				(justify mirror)
			)
		)
		(sheetname "/X710-AT2 power/")
		(sheetfile "x710-at2-power.kicad_sch")
		(attr smd)
		(fp_rect
			(start -0.925 0.47)
			(end 0.925 -0.47)
			(stroke
				(width 0.05)
				(type default)
			)
			(fill no)
			(layer "B.CrtYd")
		)
		(fp_line
			(start 0.504 0.25)
			(end 0.504 -0.248)
			(stroke
				(width 0.15)
				(type solid)
			)
			(layer "B.Fab")
		)
		(fp_line
			(start 0.504 -0.248)
			(end -0.494 -0.248)
			(stroke
				(width 0.15)
				(type solid)
			)
			(layer "B.Fab")
		)
		(fp_line
			(start -0.494 0.25)
			(end 0.504 0.25)
			(stroke
				(width 0.15)
				(type solid)
			)
			(layer "B.Fab")
		)
		(fp_line
			(start -0.494 -0.248)
			(end -0.494 0.25)
			(stroke
				(width 0.15)
				(type solid)
			)
			(layer "B.Fab")
		)
		(fp_text user "Author: Antmicro"
			(at -0.939 -3.399 0)
			(layer "B.Fab")
			(effects
				(font
					(size 0.7 0.7)
					(thickness 0.15)
				)
				(justify left bottom mirror)
			)
		)
		(fp_text user "License: Apache-2.0"
			(at -0.939 -5.799 0)
			(layer "B.Fab")
			(effects
				(font
					(size 0.7 0.7)
					(thickness 0.15)
				)
				(justify left bottom mirror)
			)
		)
		(fp_text user "${REFERENCE}"
			(at -0.939 -4.599 0)
			(layer "B.Fab")
			(effects
				(font
					(size 0.7 0.7)
					(thickness 0.15)
				)
				(justify left bottom mirror)
			)
		)
		(pad "1" smd roundrect
			(at -0.48 0 180)
			(size 0.59 0.64)
			(layers "B.Cu" "B.Mask" "B.Paste")
			(roundrect_rratio 0.25)
			(net 23 "GND")
			(pintype "passive")
		)
		(pad "2" smd roundrect
			(at 0.48 0 180)
			(size 0.59 0.64)
			(layers "B.Cu" "B.Mask" "B.Paste")
			(roundrect_rratio 0.25)
			(net 1 "VCCA")
			(pintype "passive")
		)
	)
	(footprint "antmicro-footprints:TP_SMD_0.75mm"
		(layer "B.Cu")
		(at 183.75 83.25 90)
		(property "Reference" "TP18"
			(at -12 0.75 270)
			(layer "B.SilkS")
			(effects
				(font
					(size 0.7 0.7)
					(thickness 0.15)
				)
				(justify left bottom mirror)
			)
		)
		(property "Value" "TP_0.75mm_SMD"
			(at 0 -1.2 270)
			(layer "B.Fab")
			(effects
				(font
					(size 0.7 0.7)
					(thickness 0.15)
				)
				(justify left bottom mirror)
			)
		)
		(property "Description" "SMT test point"
			(at 0 0 270)
			(layer "B.Fab")
			(hide yes)
			(effects
				(font
					(size 1.27 1.27)
					(thickness 0.15)
				)
				(justify mirror)
			)
		)
		(property "MPN" ""
			(at 0 0 90)
			(unlocked yes)
			(layer "B.Fab")
			(hide yes)
			(effects
				(font
					(size 1 1)
					(thickness 0.15)
				)
				(justify mirror)
			)
		)
		(property "Manufacturer" ""
			(at 0 0 90)
			(unlocked yes)
			(layer "B.Fab")
			(hide yes)
			(effects
				(font
					(size 1 1)
					(thickness 0.15)
				)
				(justify mirror)
			)
		)
		(property "Author" "Antmicro"
			(at 0 0 90)
			(unlocked yes)
			(layer "B.Fab")
			(hide yes)
			(effects
				(font
					(size 1 1)
					(thickness 0.15)
				)
				(justify mirror)
			)
		)
		(property "License" "Apache-2.0"
			(at 0 0 90)
			(unlocked yes)
			(layer "B.Fab")
			(hide yes)
			(effects
				(font
					(size 1 1)
					(thickness 0.15)
				)
				(justify mirror)
			)
		)
		(sheetname "/X710 DCDC converters/")
		(sheetfile "DCDC_converters_X710.kicad_sch")
		(attr exclude_from_pos_files exclude_from_bom)
		(fp_circle
			(center 0 0)
			(end 0.475 0)
			(stroke
				(width 0.05)
				(type default)
			)
			(fill no)
			(layer "B.CrtYd")
		)
		(fp_text user "${REFERENCE}"
			(at -0.4 -2.7 270)
			(layer "B.Fab")
			(effects
				(font
					(size 0.7 0.7)
					(thickness 0.15)
				)
				(justify left bottom mirror)
			)
		)
		(fp_text user "License: Apache-2.0"
			(at -0.4 -5.101 270)
			(layer "B.Fab")
			(effects
				(font
					(size 0.7 0.7)
					(thickness 0.15)
				)
				(justify left bottom mirror)
			)
		)
		(fp_text user "Author: Antmicro"
			(at -0.4 -3.901 270)
			(layer "B.Fab")
			(effects
				(font
					(size 0.7 0.7)
					(thickness 0.15)
				)
				(justify left bottom mirror)
			)
		)
		(pad "1" smd circle
			(at 0 0 90)
			(size 0.75 0.75)
			(layers "B.Cu" "B.Mask")
			(net 136 "+1V0")
			(pinfunction "1")
			(pintype "passive")
		)
	)
	(footprint "antmicro-footprints:R_0402_1005Metric"
		(layer "B.Cu")
		(at 140.600001 116.124999)
		(descr "Resistor SMD 0402")
		(tags "resistor SMD 0402")
		(property "Reference" "R35"
			(at 19.525001 -7.450001 180)
			(layer "B.SilkS")
			(effects
				(font
					(size 0.7 0.7)
					(thickness 0.15)
				)
				(justify mirror)
			)
		)
		(property "Value" "R_2k2_0402"
			(at -1.011843 -1.772047 180)
			(layer "B.Fab")
			(effects
				(font
					(size 0.7 0.7)
					(thickness 0.15)
				)
				(justify left bottom mirror)
			)
		)
		(property "Datasheet" "https://www.bourns.com/docs/product-datasheets/cr.pdf"
			(at 0 0 180)
			(layer "B.Fab")
			(hide yes)
			(effects
				(font
					(size 1.27 1.27)
					(thickness 0.15)
				)
				(justify mirror)
			)
		)
		(property "Description" "SMD Chip Resistor, 2.2 kohm, ± 1%, 62.5 mW, 0402 [1005 Metric], Thick Film, General Purpose"
			(at 0 0 180)
			(layer "B.Fab")
			(hide yes)
			(effects
				(font
					(size 1.27 1.27)
					(thickness 0.15)
				)
				(justify mirror)
			)
		)
		(property "MPN" "CR0402-FX-2201GLF"
			(at 0 0 0)
			(unlocked yes)
			(layer "B.Fab")
			(hide yes)
			(effects
				(font
					(size 1 1)
					(thickness 0.15)
				)
				(justify mirror)
			)
		)
		(property "Manufacturer" "Bourns"
			(at 0 0 0)
			(unlocked yes)
			(layer "B.Fab")
			(hide yes)
			(effects
				(font
					(size 1 1)
					(thickness 0.15)
				)
				(justify mirror)
			)
		)
		(property "License" "Apache-2.0"
			(at 0 0 0)
			(unlocked yes)
			(layer "B.Fab")
			(hide yes)
			(effects
				(font
					(size 1 1)
					(thickness 0.15)
				)
				(justify mirror)
			)
		)
		(property "Val" "2k2"
			(at 0 0 0)
			(unlocked yes)
			(layer "B.Fab")
			(hide yes)
			(effects
				(font
					(size 1 1)
					(thickness 0.15)
				)
				(justify mirror)
			)
		)
		(property "Tolerance" "1%"
			(at 0 0 0)
			(unlocked yes)
			(layer "B.Fab")
			(hide yes)
			(effects
				(font
					(size 1 1)
					(thickness 0.15)
				)
				(justify mirror)
			)
		)
		(property "Author" "Antmicro"
			(at 0 0 0)
			(unlocked yes)
			(layer "B.Fab")
			(hide yes)
			(effects
				(font
					(size 1 1)
					(thickness 0.15)
				)
				(justify mirror)
			)
		)
		(sheetname "/TB Controller/")
		(sheetfile "tb.kicad_sch")
		(attr smd)
		(fp_rect
			(start -0.925 0.47)
			(end 0.925 -0.47)
			(stroke
				(width 0.05)
				(type default)
			)
			(fill no)
			(layer "B.CrtYd")
		)
		(fp_rect
			(start -0.5 0.25)
			(end 0.5 -0.25)
			(stroke
				(width 0.15)
				(type solid)
			)
			(fill no)
			(layer "B.Fab")
		)
		(fp_text user "Author: Antmicro"
			(at -0.95 -4.169 180)
			(layer "B.Fab")
			(effects
				(font
					(size 0.7 0.7)
					(thickness 0.15)
				)
				(justify left bottom mirror)
			)
		)
		(fp_text user "${REFERENCE}"
			(at -0.95 -3.168 180)
			(layer "B.Fab")
			(effects
				(font
					(size 0.7 0.7)
					(thickness 0.15)
				)
				(justify left bottom mirror)
			)
		)
		(fp_text user "License: Apache-2.0"
			(at -0.95 -5.169 180)
			(layer "B.Fab")
			(effects
				(font
					(size 0.7 0.7)
					(thickness 0.15)
				)
				(justify left bottom mirror)
			)
		)
		(pad "1" smd roundrect
			(at -0.48 0)
			(size 0.59 0.64)
			(layers "B.Cu" "B.Mask" "B.Paste")
			(roundrect_rratio 0.25)
			(net 23 "GND")
			(pintype "passive")
		)
		(pad "2" smd roundrect
			(at 0.48 0)
			(size 0.59 0.64)
			(layers "B.Cu" "B.Mask" "B.Paste")
			(roundrect_rratio 0.25)
			(net 218 "Net-(U4C-DPSNK0_DDC_CLK)")
			(pintype "passive")
		)
	)
	(footprint "antmicro-footprints:R_0402_1005Metric"
		(layer "B.Cu")
		(at 127.8 144.4 90)
		(descr "Resistor SMD 0402")
		(tags "resistor SMD 0402")
		(property "Reference" "R30"
			(at 1.15 2.45 270)
			(layer "B.SilkS")
			(effects
				(font
					(size 0.7 0.7)
					(thickness 0.15)
				)
				(justify left bottom mirror)
			)
		)
		(property "Value" "R_5k1_0402"
			(at -1.011843 -1.772047 270)
			(layer "B.Fab")
			(effects
				(font
					(size 0.7 0.7)
					(thickness 0.15)
				)
				(justify left bottom mirror)
			)
		)
		(property "Datasheet" "https://www.bourns.com/docs/product-datasheets/cr.pdf"
			(at 0 0 270)
			(layer "B.Fab")
			(hide yes)
			(effects
				(font
					(size 1.27 1.27)
					(thickness 0.15)
				)
				(justify mirror)
			)
		)
		(property "Description" "SMD Chip Resistor, 5.1 kohm, ± 1%, 63 mW, 0402 [1005 Metric], Thick Film, General Purpose"
			(at 0 0 270)
			(layer "B.Fab")
			(hide yes)
			(effects
				(font
					(size 1.27 1.27)
					(thickness 0.15)
				)
				(justify mirror)
			)
		)
		(property "MPN" "CR0402-FX-5101GLF"
			(at 0 0 90)
			(unlocked yes)
			(layer "B.Fab")
			(hide yes)
			(effects
				(font
					(size 1 1)
					(thickness 0.15)
				)
				(justify mirror)
			)
		)
		(property "Manufacturer" "Bourns"
			(at 0 0 90)
			(unlocked yes)
			(layer "B.Fab")
			(hide yes)
			(effects
				(font
					(size 1 1)
					(thickness 0.15)
				)
				(justify mirror)
			)
		)
		(property "License" "Apache-2.0"
			(at 0 0 90)
			(unlocked yes)
			(layer "B.Fab")
			(hide yes)
			(effects
				(font
					(size 1 1)
					(thickness 0.15)
				)
				(justify mirror)
			)
		)
		(property "Val" "5k1"
			(at 0 0 90)
			(unlocked yes)
			(layer "B.Fab")
			(hide yes)
			(effects
				(font
					(size 1 1)
					(thickness 0.15)
				)
				(justify mirror)
			)
		)
		(property "Tolerance" "1%"
			(at 0 0 90)
			(unlocked yes)
			(layer "B.Fab")
			(hide yes)
			(effects
				(font
					(size 1 1)
					(thickness 0.15)
				)
				(justify mirror)
			)
		)
		(property "Author" "Antmicro"
			(at 0 0 90)
			(unlocked yes)
			(layer "B.Fab")
			(hide yes)
			(effects
				(font
					(size 1 1)
					(thickness 0.15)
				)
				(justify mirror)
			)
		)
		(sheetname "/PD and TB DC-DC/")
		(sheetfile "PD_and_TB_DC_DC.kicad_sch")
		(attr smd)
		(fp_rect
			(start -0.925 0.47)
			(end 0.925 -0.47)
			(stroke
				(width 0.05)
				(type default)
			)
			(fill no)
			(layer "B.CrtYd")
		)
		(fp_rect
			(start -0.5 0.25)
			(end 0.5 -0.25)
			(stroke
				(width 0.15)
				(type solid)
			)
			(fill no)
			(layer "B.Fab")
		)
		(fp_text user "Author: Antmicro"
			(at -0.95 -4.169 270)
			(layer "B.Fab")
			(effects
				(font
					(size 0.7 0.7)
					(thickness 0.15)
				)
				(justify left bottom mirror)
			)
		)
		(fp_text user "License: Apache-2.0"
			(at -0.95 -5.169 270)
			(layer "B.Fab")
			(effects
				(font
					(size 0.7 0.7)
					(thickness 0.15)
				)
				(justify left bottom mirror)
			)
		)
		(fp_text user "${REFERENCE}"
			(at -0.95 -3.168 270)
			(layer "B.Fab")
			(effects
				(font
					(size 0.7 0.7)
					(thickness 0.15)
				)
				(justify left bottom mirror)
			)
		)
		(pad "1" smd roundrect
			(at -0.48 0 90)
			(size 0.59 0.64)
			(layers "B.Cu" "B.Mask" "B.Paste")
			(roundrect_rratio 0.25)
			(net 23 "GND")
			(pintype "passive")
		)
		(pad "2" smd roundrect
			(at 0.48 0 90)
			(size 0.59 0.64)
			(layers "B.Cu" "B.Mask" "B.Paste")
			(roundrect_rratio 0.25)
			(net 305 "/PD and TB DC-DC/USB3.CC2")
			(pintype "passive")
		)
	)
	(footprint "antmicro-footprints:R_0402_1005Metric"
		(layer "B.Cu")
		(at 137.5 127.6)
		(descr "Resistor SMD 0402")
		(tags "resistor SMD 0402")
		(property "Reference" "R51"
			(at 19.525001 -7.450001 180)
			(layer "B.SilkS")
			(effects
				(font
					(size 0.7 0.7)
					(thickness 0.15)
				)
				(justify mirror)
			)
		)
		(property "Value" "R_10k_0402"
			(at -1.011843 -1.772047 180)
			(layer "B.Fab")
			(effects
				(font
					(size 0.7 0.7)
					(thickness 0.15)
				)
				(justify left bottom mirror)
			)
		)
		(property "Datasheet" "https://www.bourns.com/docs/product-datasheets/cr.pdf"
			(at 0 0 180)
			(layer "B.Fab")
			(hide yes)
			(effects
				(font
					(size 1.27 1.27)
					(thickness 0.15)
				)
				(justify mirror)
			)
		)
		(property "Description" "SMD Chip Resistor, 10 kohm, ± 1%, 62.5 mW, 0402 [1005 Metric], Thick Film, General Purpose"
			(at 0 0 180)
			(layer "B.Fab")
			(hide yes)
			(effects
				(font
					(size 1.27 1.27)
					(thickness 0.15)
				)
				(justify mirror)
			)
		)
		(property "MPN" "CR0402-FX-1002GLF"
			(at 0 0 0)
			(unlocked yes)
			(layer "B.Fab")
			(hide yes)
			(effects
				(font
					(size 1 1)
					(thickness 0.15)
				)
				(justify mirror)
			)
		)
		(property "Manufacturer" "Bourns"
			(at 0 0 0)
			(unlocked yes)
			(layer "B.Fab")
			(hide yes)
			(effects
				(font
					(size 1 1)
					(thickness 0.15)
				)
				(justify mirror)
			)
		)
		(property "License" "Apache-2.0"
			(at 0 0 0)
			(unlocked yes)
			(layer "B.Fab")
			(hide yes)
			(effects
				(font
					(size 1 1)
					(thickness 0.15)
				)
				(justify mirror)
			)
		)
		(property "Val" "10k"
			(at 0 0 0)
			(unlocked yes)
			(layer "B.Fab")
			(hide yes)
			(effects
				(font
					(size 1 1)
					(thickness 0.15)
				)
				(justify mirror)
			)
		)
		(property "Tolerance" "1%"
			(at 0 0 0)
			(unlocked yes)
			(layer "B.Fab")
			(hide yes)
			(effects
				(font
					(size 1 1)
					(thickness 0.15)
				)
				(justify mirror)
			)
		)
		(property "Author" "Antmicro"
			(at 0 0 0)
			(unlocked yes)
			(layer "B.Fab")
			(hide yes)
			(effects
				(font
					(size 1 1)
					(thickness 0.15)
				)
				(justify mirror)
			)
		)
		(sheetname "/TB Controller/")
		(sheetfile "tb.kicad_sch")
		(attr smd)
		(fp_rect
			(start -0.925 0.47)
			(end 0.925 -0.47)
			(stroke
				(width 0.05)
				(type default)
			)
			(fill no)
			(layer "B.CrtYd")
		)
		(fp_rect
			(start -0.5 0.25)
			(end 0.5 -0.25)
			(stroke
				(width 0.15)
				(type solid)
			)
			(fill no)
			(layer "B.Fab")
		)
		(fp_text user "License: Apache-2.0"
			(at -0.95 -5.169 180)
			(layer "B.Fab")
			(effects
				(font
					(size 0.7 0.7)
					(thickness 0.15)
				)
				(justify left bottom mirror)
			)
		)
		(fp_text user "${REFERENCE}"
			(at -0.95 -3.168 180)
			(layer "B.Fab")
			(effects
				(font
					(size 0.7 0.7)
					(thickness 0.15)
				)
				(justify left bottom mirror)
			)
		)
		(fp_text user "Author: Antmicro"
			(at -0.95 -4.169 180)
			(layer "B.Fab")
			(effects
				(font
					(size 0.7 0.7)
					(thickness 0.15)
				)
				(justify left bottom mirror)
			)
		)
		(pad "1" smd roundrect
			(at -0.48 0)
			(size 0.59 0.64)
			(layers "B.Cu" "B.Mask" "B.Paste")
			(roundrect_rratio 0.25)
			(net 194 "Net-(U4C-POC_GPIO_3)")
			(pintype "passive")
		)
		(pad "2" smd roundrect
			(at 0.48 0)
			(size 0.59 0.64)
			(layers "B.Cu" "B.Mask" "B.Paste")
			(roundrect_rratio 0.25)
			(net 23 "GND")
			(pintype "passive")
		)
	)
)
